(kicad_pcb
	(version 20241229)
	(generator "pcbnew")
	(generator_version "9.0")
	(general
		(thickness 1.63)
		(legacy_teardrops no)
	)
	(paper "A4")
	(title_block
		(title "CM4 Baseboard")
		(date "2026-01-05")
		(rev "1.1.1")
		(company "Antmicro Ltd")
		(comment 1 "www.antmicro.com")
		(comment 9 "footprints 79-84 of 506")
	)
	(layers
		(0 "F.Cu" signal)
		(4 "In1.Cu" power)
		(6 "In2.Cu" power)
		(8 "In3.Cu" signal)
		(10 "In4.Cu" signal)
		(2 "B.Cu" signal)
		(9 "F.Adhes" user "F.Adhesive")
		(11 "B.Adhes" user "B.Adhesive")
		(13 "F.Paste" user)
		(15 "B.Paste" user)
		(5 "F.SilkS" user "F.Silkscreen")
		(7 "B.SilkS" user "B.Silkscreen")
		(1 "F.Mask" user)
		(3 "B.Mask" user)
		(17 "Dwgs.User" user "User.Drawings")
		(19 "Cmts.User" user "User.Comments")
		(21 "Eco1.User" user "User.Eco1")
		(23 "Eco2.User" user "User.Eco2")
		(25 "Edge.Cuts" user)
		(27 "Margin" user)
		(31 "F.CrtYd" user "F.Courtyard")
		(29 "B.CrtYd" user "B.Courtyard")
		(35 "F.Fab" user)
		(33 "B.Fab" user)
	)
	(footprint "antmicro-footprints:C_0805_2012Metric"
		(layer "F.Cu")
		(at 76.237962 124.2465 180)
		(descr "Capacitor SMD 0805")
		(tags "capacitor SMD 0805")
		(property "Reference" "C932"
			(at -0.662038 -1.8785 0)
			(layer "F.SilkS")
			(effects
				(font
					(size 0.7 0.7)
					(thickness 0.15)
				)
				(justify right bottom)
			)
		)
		(property "Value" "C_22u_25V_0805"
			(at -2.055717 1.963152 0)
			(layer "F.Fab")
			(effects
				(font
					(size 0.7 0.7)
					(thickness 0.15)
				)
				(justify right bottom)
			)
		)
		(property "Datasheet" "https://product.samsungsem.com/mlcc/CL21A226MAYNNN.do"
			(at 0 0 180)
			(layer "F.Fab")
			(hide yes)
			(effects
				(font
					(size 1.27 1.27)
					(thickness 0.15)
				)
			)
		)
		(property "Manufacturer" "Samsung Electro-Mechanics"
			(at 0 0 180)
			(unlocked yes)
			(layer "F.Fab")
			(hide yes)
			(effects
				(font
					(size 1 1)
					(thickness 0.15)
				)
			)
		)
		(property "MPN" "CL21A226MAYNNNE"
			(at 0 0 180)
			(unlocked yes)
			(layer "F.Fab")
			(hide yes)
			(effects
				(font
					(size 1 1)
					(thickness 0.15)
				)
			)
		)
		(property "Val" "22u"
			(at 0 0 180)
			(unlocked yes)
			(layer "F.Fab")
			(hide yes)
			(effects
				(font
					(size 1 1)
					(thickness 0.15)
				)
			)
		)
		(property "License" "Apache-2.0"
			(at 0 0 180)
			(unlocked yes)
			(layer "F.Fab")
			(hide yes)
			(effects
				(font
					(size 1 1)
					(thickness 0.15)
				)
			)
		)
		(property "Author" "Antmicro"
			(at 0 0 180)
			(unlocked yes)
			(layer "F.Fab")
			(hide yes)
			(effects
				(font
					(size 1 1)
					(thickness 0.15)
				)
			)
		)
		(property "Voltage" "25V"
			(at 0 0 180)
			(unlocked yes)
			(layer "F.Fab")
			(hide yes)
			(effects
				(font
					(size 1 1)
					(thickness 0.15)
				)
			)
		)
		(property "Dielectric" "X5R"
			(at 0 0 180)
			(unlocked yes)
			(layer "F.Fab")
			(hide yes)
			(effects
				(font
					(size 1 1)
					(thickness 0.15)
				)
			)
		)
		(property "Public" "False"
			(at 0 0 180)
			(unlocked yes)
			(layer "F.Fab")
			(hide yes)
			(effects
				(font
					(size 1 1)
					(thickness 0.15)
				)
			)
		)
		(sheetname "/USB/")
		(sheetfile "usb.kicad_sch")
		(attr smd)
		(fp_line
			(start -0.3 0.7)
			(end 0.3 0.7)
			(stroke
				(width 0.15)
				(type solid)
			)
			(layer "F.SilkS")
		)
		(fp_line
			(start -0.3 -0.7)
			(end 0.3 -0.7)
			(stroke
				(width 0.15)
				(type solid)
			)
			(layer "F.SilkS")
		)
		(fp_rect
			(start 1.95 -0.9)
			(end -1.95 0.9)
			(stroke
				(width 0.05)
				(type default)
			)
			(fill no)
			(layer "F.CrtYd")
		)
		(fp_rect
			(start -0.95 -0.675)
			(end 0.95 0.675)
			(stroke
				(width 0.15)
				(type solid)
			)
			(fill no)
			(layer "F.Fab")
		)
		(fp_text user "Author: Antmicro"
			(at -1.9 5.947 180)
			(layer "F.Fab")
			(effects
				(font
					(size 0.7 0.7)
					(thickness 0.15)
				)
				(justify left bottom)
			)
		)
		(fp_text user "${REFERENCE}"
			(at -1.9 3.947 180)
			(layer "F.Fab")
			(effects
				(font
					(size 0.7 0.7)
					(thickness 0.15)
				)
				(justify left bottom)
			)
		)
		(fp_text user "License: Apache-2.0"
			(at -1.9 4.947 180)
			(layer "F.Fab")
			(effects
				(font
					(size 0.7 0.7)
					(thickness 0.15)
				)
				(justify left bottom)
			)
		)
		(pad "1" smd roundrect
			(at -1.1 0 180)
			(size 1.2 1.3)
			(layers "F.Cu" "F.Mask" "F.Paste")
			(roundrect_rratio 0.25)
			(net 26 "/USB/USBD_VBUS")
			(pintype "passive")
		)
		(pad "2" smd roundrect
			(at 1.1 0 180)
			(size 1.2 1.3)
			(layers "F.Cu" "F.Mask" "F.Paste")
			(roundrect_rratio 0.25)
			(net 3 "GND")
			(pintype "passive")
		)
	)
	(footprint "antmicro-footprints:R_0402_1005Metric"
		(layer "F.Cu")
		(at 101.167962 133.8915 180)
		(descr "Resistor SMD 0402")
		(tags "resistor SMD 0402")
		(property "Reference" "R927"
			(at -3.74 -0.465 0)
			(layer "F.SilkS")
			(effects
				(font
					(size 0.7 0.7)
					(thickness 0.15)
				)
				(justify right bottom)
			)
		)
		(property "Value" "R_4k7_0402"
			(at -1.011843 1.772047 0)
			(layer "F.Fab")
			(effects
				(font
					(size 0.7 0.7)
					(thickness 0.15)
				)
				(justify right bottom)
			)
		)
		(property "Datasheet" "https://www.bourns.com/docs/product-datasheets/cr.pdf"
			(at 0 0 180)
			(layer "F.Fab")
			(hide yes)
			(effects
				(font
					(size 1.27 1.27)
					(thickness 0.15)
				)
			)
		)
		(property "Manufacturer" "Bourns"
			(at 0 0 180)
			(unlocked yes)
			(layer "F.Fab")
			(hide yes)
			(effects
				(font
					(size 1 1)
					(thickness 0.15)
				)
			)
		)
		(property "MPN" "CR0402-FX-4701GLF"
			(at 0 0 180)
			(unlocked yes)
			(layer "F.Fab")
			(hide yes)
			(effects
				(font
					(size 1 1)
					(thickness 0.15)
				)
			)
		)
		(property "Val" "4k7"
			(at 0 0 180)
			(unlocked yes)
			(layer "F.Fab")
			(hide yes)
			(effects
				(font
					(size 1 1)
					(thickness 0.15)
				)
			)
		)
		(property "License" "Apache-2.0"
			(at 0 0 180)
			(unlocked yes)
			(layer "F.Fab")
			(hide yes)
			(effects
				(font
					(size 1 1)
					(thickness 0.15)
				)
			)
		)
		(property "Author" "Antmicro"
			(at 0 0 180)
			(unlocked yes)
			(layer "F.Fab")
			(hide yes)
			(effects
				(font
					(size 1 1)
					(thickness 0.15)
				)
			)
		)
		(property "Tolerance" "1%"
			(at 0 0 180)
			(unlocked yes)
			(layer "F.Fab")
			(hide yes)
			(effects
				(font
					(size 1 1)
					(thickness 0.15)
				)
			)
		)
		(sheetname "/USB/")
		(sheetfile "usb.kicad_sch")
		(attr smd)
		(fp_rect
			(start -0.925 -0.47)
			(end 0.925 0.47)
			(stroke
				(width 0.05)
				(type default)
			)
			(fill no)
			(layer "F.CrtYd")
		)
		(fp_rect
			(start -0.5 -0.25)
			(end 0.5 0.25)
			(stroke
				(width 0.15)
				(type solid)
			)
			(fill no)
			(layer "F.Fab")
		)
		(fp_text user "${REFERENCE}"
			(at -0.95 3.168 180)
			(layer "F.Fab")
			(effects
				(font
					(size 0.7 0.7)
					(thickness 0.15)
				)
				(justify left bottom)
			)
		)
		(fp_text user "License: Apache-2.0"
			(at -0.95 5.169 180)
			(layer "F.Fab")
			(effects
				(font
					(size 0.7 0.7)
					(thickness 0.15)
				)
				(justify left bottom)
			)
		)
		(fp_text user "Author: Antmicro"
			(at -0.95 4.169 180)
			(layer "F.Fab")
			(effects
				(font
					(size 0.7 0.7)
					(thickness 0.15)
				)
				(justify left bottom)
			)
		)
		(pad "1" smd roundrect
			(at -0.48 0 180)
			(size 0.59 0.64)
			(layers "F.Cu" "F.Mask" "F.Paste")
			(roundrect_rratio 0.25)
			(net 3 "GND")
			(pintype "passive")
		)
		(pad "2" smd roundrect
			(at 0.48 0 180)
			(size 0.59 0.64)
			(layers "F.Cu" "F.Mask" "F.Paste")
			(roundrect_rratio 0.25)
			(net 127 "Net-(Q903-G)")
			(pintype "passive")
		)
	)
	(footprint "antmicro-footprints:R_0402_1005Metric"
		(layer "F.Cu")
		(at 56.867962 135.7915 180)
		(descr "Resistor SMD 0402")
		(tags "resistor SMD 0402")
		(property "Reference" "R420"
			(at -1.45 -1.415 0)
			(layer "F.SilkS")
			(effects
				(font
					(size 0.7 0.7)
					(thickness 0.15)
				)
				(justify right bottom)
			)
		)
		(property "Value" "R_100k_0402"
			(at -1.011843 1.772047 0)
			(layer "F.Fab")
			(effects
				(font
					(size 0.7 0.7)
					(thickness 0.15)
				)
				(justify right bottom)
			)
		)
		(property "Datasheet" "https://www.bourns.com/docs/product-datasheets/cr.pdf"
			(at 0 0 180)
			(layer "F.Fab")
			(hide yes)
			(effects
				(font
					(size 1.27 1.27)
					(thickness 0.15)
				)
			)
		)
		(property "Manufacturer" "Bourns"
			(at 0 0 180)
			(unlocked yes)
			(layer "F.Fab")
			(hide yes)
			(effects
				(font
					(size 1 1)
					(thickness 0.15)
				)
			)
		)
		(property "MPN" "CR0402-FX-1003GLF"
			(at 0 0 180)
			(unlocked yes)
			(layer "F.Fab")
			(hide yes)
			(effects
				(font
					(size 1 1)
					(thickness 0.15)
				)
			)
		)
		(property "Val" "100k"
			(at 0 0 180)
			(unlocked yes)
			(layer "F.Fab")
			(hide yes)
			(effects
				(font
					(size 1 1)
					(thickness 0.15)
				)
			)
		)
		(property "License" "Apache-2.0"
			(at 0 0 180)
			(unlocked yes)
			(layer "F.Fab")
			(hide yes)
			(effects
				(font
					(size 1 1)
					(thickness 0.15)
				)
			)
		)
		(property "Author" "Antmicro"
			(at 0 0 180)
			(unlocked yes)
			(layer "F.Fab")
			(hide yes)
			(effects
				(font
					(size 1 1)
					(thickness 0.15)
				)
			)
		)
		(property "Tolerance" "1%"
			(at 0 0 180)
			(unlocked yes)
			(layer "F.Fab")
			(hide yes)
			(effects
				(font
					(size 1 1)
					(thickness 0.15)
				)
			)
		)
		(sheetname "/Ethernet/")
		(sheetfile "ethernet.kicad_sch")
		(attr smd exclude_from_pos_files exclude_from_bom dnp)
		(fp_rect
			(start -0.925 -0.47)
			(end 0.925 0.47)
			(stroke
				(width 0.05)
				(type default)
			)
			(fill no)
			(layer "F.CrtYd")
		)
		(fp_rect
			(start -0.5 -0.25)
			(end 0.5 0.25)
			(stroke
				(width 0.15)
				(type solid)
			)
			(fill no)
			(layer "F.Fab")
		)
		(fp_text user "License: Apache-2.0"
			(at -0.95 5.169 180)
			(layer "F.Fab")
			(effects
				(font
					(size 0.7 0.7)
					(thickness 0.15)
				)
				(justify left bottom)
			)
		)
		(fp_text user "Author: Antmicro"
			(at -0.95 4.169 180)
			(layer "F.Fab")
			(effects
				(font
					(size 0.7 0.7)
					(thickness 0.15)
				)
				(justify left bottom)
			)
		)
		(fp_text user "${REFERENCE}"
			(at -0.95 3.168 180)
			(layer "F.Fab")
			(effects
				(font
					(size 0.7 0.7)
					(thickness 0.15)
				)
				(justify left bottom)
			)
		)
		(pad "1" smd roundrect
			(at -0.48 0 180)
			(size 0.59 0.64)
			(layers "F.Cu" "F.Mask" "F.Paste")
			(roundrect_rratio 0.25)
			(net 1 "GNDD")
			(pintype "passive")
		)
		(pad "2" smd roundrect
			(at 0.48 0 180)
			(size 0.59 0.64)
			(layers "F.Cu" "F.Mask" "F.Paste")
			(roundrect_rratio 0.25)
			(net 126 "/Ethernet/ULS-12_CTRL")
			(pintype "passive")
		)
	)
	(footprint "antmicro-footprints:C_0402_1005Metric"
		(layer "F.Cu")
		(at 88.592962 143.907236 180)
		(descr "Capacitor SMD 0402")
		(tags "capacitor SMD 0402")
		(property "Reference" "C913"
			(at -1.187038 -1.412764 0)
			(layer "F.SilkS")
			(effects
				(font
					(size 0.7 0.7)
					(thickness 0.15)
				)
				(justify right bottom)
			)
		)
		(property "Value" "C_100n_0402"
			(at -1.022927 2.155213 0)
			(layer "F.Fab")
			(effects
				(font
					(size 0.7 0.7)
					(thickness 0.15)
				)
				(justify right bottom)
			)
		)
		(property "Datasheet" "https://www.murata.com/products/productdetail?partno=GRM155R61H104KE14%23"
			(at 0 0 180)
			(layer "F.Fab")
			(hide yes)
			(effects
				(font
					(size 1.27 1.27)
					(thickness 0.15)
				)
			)
		)
		(property "Manufacturer" "Murata"
			(at 0 0 180)
			(unlocked yes)
			(layer "F.Fab")
			(hide yes)
			(effects
				(font
					(size 1 1)
					(thickness 0.15)
				)
			)
		)
		(property "MPN" "GRM155R61H104KE14D"
			(at 0 0 180)
			(unlocked yes)
			(layer "F.Fab")
			(hide yes)
			(effects
				(font
					(size 1 1)
					(thickness 0.15)
				)
			)
		)
		(property "Val" "100n"
			(at 0 0 180)
			(unlocked yes)
			(layer "F.Fab")
			(hide yes)
			(effects
				(font
					(size 1 1)
					(thickness 0.15)
				)
			)
		)
		(property "License" "Apache-2.0"
			(at 0 0 180)
			(unlocked yes)
			(layer "F.Fab")
			(hide yes)
			(effects
				(font
					(size 1 1)
					(thickness 0.15)
				)
			)
		)
		(property "Author" "Antmicro"
			(at 0 0 180)
			(unlocked yes)
			(layer "F.Fab")
			(hide yes)
			(effects
				(font
					(size 1 1)
					(thickness 0.15)
				)
			)
		)
		(property "Voltage" "50V"
			(at 0 0 180)
			(unlocked yes)
			(layer "F.Fab")
			(hide yes)
			(effects
				(font
					(size 1 1)
					(thickness 0.15)
				)
			)
		)
		(property "Dielectric" "X5R"
			(at 0 0 180)
			(unlocked yes)
			(layer "F.Fab")
			(hide yes)
			(effects
				(font
					(size 1 1)
					(thickness 0.15)
				)
			)
		)
		(sheetname "/USB/")
		(sheetfile "usb.kicad_sch")
		(attr smd)
		(fp_rect
			(start -0.925 -0.47)
			(end 0.925 0.47)
			(stroke
				(width 0.05)
				(type default)
			)
			(fill no)
			(layer "F.CrtYd")
		)
		(fp_line
			(start 0.504 0.248)
			(end -0.494 0.248)
			(stroke
				(width 0.15)
				(type solid)
			)
			(layer "F.Fab")
		)
		(fp_line
			(start 0.504 -0.25)
			(end 0.504 0.248)
			(stroke
				(width 0.15)
				(type solid)
			)
			(layer "F.Fab")
		)
		(fp_line
			(start -0.494 0.248)
			(end -0.494 -0.25)
			(stroke
				(width 0.15)
				(type solid)
			)
			(layer "F.Fab")
		)
		(fp_line
			(start -0.494 -0.25)
			(end 0.504 -0.25)
			(stroke
				(width 0.15)
				(type solid)
			)
			(layer "F.Fab")
		)
		(fp_text user "Author: Antmicro"
			(at -0.939 3.399 180)
			(layer "F.Fab")
			(effects
				(font
					(size 0.7 0.7)
					(thickness 0.15)
				)
				(justify left bottom)
			)
		)
		(fp_text user "${REFERENCE}"
			(at -0.939 4.599 180)
			(layer "F.Fab")
			(effects
				(font
					(size 0.7 0.7)
					(thickness 0.15)
				)
				(justify left bottom)
			)
		)
		(fp_text user "License: Apache-2.0"
			(at -0.939 5.799 180)
			(layer "F.Fab")
			(effects
				(font
					(size 0.7 0.7)
					(thickness 0.15)
				)
				(justify left bottom)
			)
		)
		(pad "1" smd roundrect
			(at -0.48 0 180)
			(size 0.59 0.64)
			(layers "F.Cu" "F.Mask" "F.Paste")
			(roundrect_rratio 0.25)
			(net 27 "/USB/USB_3V3")
			(pintype "passive")
		)
		(pad "2" smd roundrect
			(at 0.48 0 180)
			(size 0.59 0.64)
			(layers "F.Cu" "F.Mask" "F.Paste")
			(roundrect_rratio 0.25)
			(net 3 "GND")
			(pintype "passive")
		)
	)
	(footprint "antmicro-footprints:TP_SMD_0.75mm"
		(layer "F.Cu")
		(at 74.77 153.68 180)
		(property "Reference" "TP213"
			(at 3.79 -0.22 180)
			(layer "F.SilkS")
			(effects
				(font
					(size 0.7 0.7)
					(thickness 0.15)
				)
				(justify left bottom)
			)
		)
		(property "Value" "TP_0.75mm_SMD"
			(at 0 1.2 180)
			(layer "F.Fab")
			(effects
				(font
					(size 0.7 0.7)
					(thickness 0.15)
				)
				(justify left bottom)
			)
		)
		(property "Author" "Antmicro"
			(at 0 0 180)
			(unlocked yes)
			(layer "F.Fab")
			(hide yes)
			(effects
				(font
					(size 1 1)
					(thickness 0.15)
				)
			)
		)
		(property "License" "Apache-2.0"
			(at 0 0 180)
			(unlocked yes)
			(layer "F.Fab")
			(hide yes)
			(effects
				(font
					(size 1 1)
					(thickness 0.15)
				)
			)
		)
		(property "MPN" ""
			(at 0 0 180)
			(unlocked yes)
			(layer "F.Fab")
			(hide yes)
			(effects
				(font
					(size 1 1)
					(thickness 0.15)
				)
			)
		)
		(property "Manufacturer" ""
			(at 0 0 180)
			(unlocked yes)
			(layer "F.Fab")
			(hide yes)
			(effects
				(font
					(size 1 1)
					(thickness 0.15)
				)
			)
		)
		(sheetname "/Compute module/")
		(sheetfile "compute-module.kicad_sch")
		(attr exclude_from_pos_files exclude_from_bom)
		(fp_circle
			(center 0 0)
			(end 0.475 0)
			(stroke
				(width 0.05)
				(type default)
			)
			(fill no)
			(layer "F.CrtYd")
		)
		(fp_text user "Author: Antmicro"
			(at -0.4 3.901 180)
			(layer "F.Fab")
			(effects
				(font
					(size 0.7 0.7)
					(thickness 0.15)
				)
				(justify left bottom)
			)
		)
		(fp_text user "${REFERENCE}"
			(at -0.4 2.7 180)
			(layer "F.Fab")
			(effects
				(font
					(size 0.7 0.7)
					(thickness 0.15)
				)
				(justify left bottom)
			)
		)
		(fp_text user "License: Apache-2.0"
			(at -0.4 5.101 180)
			(layer "F.Fab")
			(effects
				(font
					(size 0.7 0.7)
					(thickness 0.15)
				)
				(justify left bottom)
			)
		)
		(pad "1" smd circle
			(at 0 0 180)
			(size 0.75 0.75)
			(layers "F.Cu" "F.Mask")
			(net 18 "V_{IO}")
			(pinfunction "1")
			(pintype "passive")
		)
	)
	(footprint "antmicro-footprints:TP_SMD_0.75mm"
		(layer "F.Cu")
		(at 110.742962 146.8915 180)
		(property "Reference" "TP212"
			(at -0.907038 -3.6335 270)
			(layer "F.SilkS")
			(effects
				(font
					(size 0.7 0.7)
					(thickness 0.15)
				)
				(justify left bottom)
			)
		)
		(property "Value" "TP_0.75mm_SMD"
			(at 0 1.2 180)
			(layer "F.Fab")
			(effects
				(font
					(size 0.7 0.7)
					(thickness 0.15)
				)
				(justify left bottom)
			)
		)
		(property "Author" "Antmicro"
			(at 0 0 180)
			(unlocked yes)
			(layer "F.Fab")
			(hide yes)
			(effects
				(font
					(size 1 1)
					(thickness 0.15)
				)
			)
		)
		(property "License" "Apache-2.0"
			(at 0 0 180)
			(unlocked yes)
			(layer "F.Fab")
			(hide yes)
			(effects
				(font
					(size 1 1)
					(thickness 0.15)
				)
			)
		)
		(property "MPN" ""
			(at 0 0 180)
			(unlocked yes)
			(layer "F.Fab")
			(hide yes)
			(effects
				(font
					(size 1 1)
					(thickness 0.15)
				)
			)
		)
		(property "Manufacturer" ""
			(at 0 0 180)
			(unlocked yes)
			(layer "F.Fab")
			(hide yes)
			(effects
				(font
					(size 1 1)
					(thickness 0.15)
				)
			)
		)
		(sheetname "/Compute module/")
		(sheetfile "compute-module.kicad_sch")
		(attr exclude_from_pos_files exclude_from_bom)
		(fp_circle
			(center 0 0)
			(end 0.475 0)
			(stroke
				(width 0.05)
				(type default)
			)
			(fill no)
			(layer "F.CrtYd")
		)
		(fp_text user "License: Apache-2.0"
			(at -0.4 5.101 180)
			(layer "F.Fab")
			(effects
				(font
					(size 0.7 0.7)
					(thickness 0.15)
				)
				(justify left bottom)
			)
		)
		(fp_text user "Author: Antmicro"
			(at -0.4 3.901 180)
			(layer "F.Fab")
			(effects
				(font
					(size 0.7 0.7)
					(thickness 0.15)
				)
				(justify left bottom)
			)
		)
		(fp_text user "${REFERENCE}"
			(at -0.4 2.7 180)
			(layer "F.Fab")
			(effects
				(font
					(size 0.7 0.7)
					(thickness 0.15)
				)
				(justify left bottom)
			)
		)
		(pad "1" smd circle
			(at 0 0 180)
			(size 0.75 0.75)
			(layers "F.Cu" "F.Mask")
			(net 256 "/Compute module/VDAC_COMP")
			(pinfunction "1")
			(pintype "passive")
		)
	)
)
